(kicad_pcb
	(version 20260206)
	(generator "pcbnew")
	(generator_version "10.0")
	(general
		(thickness 1.6)
		(legacy_teardrops no)
	)
	(paper "A4")
	(title_block
		(title "fcb — Lightning_FCB_BRD.brd")
		(comment 1 "Lightning (Wiwynn / Facebook NVMe JBOF) / footprints 132-137 of 495")
	)
	(layers
		(0 "F.Cu" signal "TOP")
		(4 "In1.Cu" signal "L2GND")
		(6 "In2.Cu" signal "L3VCC")
		(2 "B.Cu" signal "BOTTOM")
		(9 "F.Adhes" user "F.Adhesive")
		(11 "B.Adhes" user "B.Adhesive")
		(13 "F.Paste" user "Package Geometry/Pastemask Top")
		(15 "B.Paste" user "Package Geometry/Pastemask Bottom")
		(5 "F.SilkS" user "Ref Des/Silkscreen Top")
		(7 "B.SilkS" user "Ref Des/Silkscreen Bottom")
		(1 "F.Mask" user "Board Geometry/Soldermask Top")
		(3 "B.Mask" user "Board Geometry/Soldermask Bottom")
		(17 "Dwgs.User" user "User.Drawings")
		(19 "Cmts.User" user "User.Comments")
		(21 "Eco1.User" user "User.Eco1")
		(23 "Eco2.User" user "User.Eco2")
		(25 "Edge.Cuts" user "Board Geometry/Outline")
		(27 "Margin" user)
		(31 "F.CrtYd" user "Package Geometry/Place Bound Top")
		(29 "B.CrtYd" user "Package Geometry/Place Bound Bottom")
		(35 "F.Fab" user "Ref Des/Assembly Top")
		(33 "B.Fab" user "Ref Des/Assembly Bottom")
	)
	(footprint ""
		(layer "F.Cu")
		(at 22.5044 -136.6012 90)
		(property "Reference" "PC87"
			(at 0 0 90)
			(layer "F.SilkS")
			(hide yes)
			(effects
				(font
					(size 1.27 1.27)
				)
			)
		)
		(property "Value" "SC220P50V2KX-3GP"
			(at 1.1811 -2.7051 90)
			(unlocked yes)
			(layer "F.Fab")
			(hide yes)
			(effects
				(font
					(size 1.016 1.016)
					(thickness 0.1524)
				)
			)
		)
		(property "Device Type" "C402H22"
			(at 1.1811 -4.2291 90)
			(unlocked yes)
			(layer "F.Fab")
			(hide yes)
			(effects
				(font
					(size 1.016 1.016)
					(thickness 0.1524)
				)
			)
		)
		(duplicate_pad_numbers_are_jumpers no)
		(fp_rect
			(start -0.4318 0.9525)
			(end 0.4318 -0.9525)
			(stroke
				(width 0)
				(type default)
			)
			(fill no)
			(layer "F.CrtYd")
		)
		(fp_rect
			(start -0.4318 0.9525)
			(end 0.4318 -0.9525)
			(stroke
				(width 0)
				(type default)
			)
			(fill no)
			(layer "F.Fab")
		)
		(pad "1" smd custom
			(at 0 -0.4445 90)
			(size 0.1524 0.1524)
			(layers "F.Cu" "F.Mask" "F.Paste")
			(net "P12VU_2490_SENSE")
			(options
				(clearance outline)
				(anchor circle)
			)
			(primitives
				(gr_poly
					(pts
						(arc
							(start 0.3048 -0.2032)
							(mid 0.275042 -0.275042)
							(end 0.2032 -0.3048)
						)
						(arc
							(start -0.2032 -0.3048)
							(mid -0.275042 -0.275042)
							(end -0.3048 -0.2032)
						)
						(arc
							(start -0.3048 0.2032)
							(mid -0.275042 0.275042)
							(end -0.2032 0.3048)
						)
						(arc
							(start 0.2032 0.3048)
							(mid 0.275042 0.275042)
							(end 0.3048 0.2032)
						)
					)
					(width 0)
					(fill yes)
				)
			)
		)
		(pad "2" smd custom
			(at 0 0.4445 90)
			(size 0.1524 0.1524)
			(layers "F.Cu" "F.Mask" "F.Paste")
			(net "P12VU_2490_VCC")
			(options
				(clearance outline)
				(anchor circle)
			)
			(primitives
				(gr_poly
					(pts
						(arc
							(start 0.3048 -0.2032)
							(mid 0.275042 -0.275042)
							(end 0.2032 -0.3048)
						)
						(arc
							(start -0.2032 -0.3048)
							(mid -0.275042 -0.275042)
							(end -0.3048 -0.2032)
						)
						(arc
							(start -0.3048 0.2032)
							(mid -0.275042 0.275042)
							(end -0.2032 0.3048)
						)
						(arc
							(start 0.2032 0.3048)
							(mid 0.275042 0.275042)
							(end 0.3048 0.2032)
						)
					)
					(width 0)
					(fill yes)
				)
			)
		)
	)
	(footprint ""
		(layer "F.Cu")
		(at 41.0464 -138.5824 90)
		(property "Reference" "PR101"
			(at 0 0 90)
			(layer "F.SilkS")
			(hide yes)
			(effects
				(font
					(size 1.27 1.27)
				)
			)
		)
		(property "Value" "100R2F-L1-GP-U"
			(at 0.064008 -3.993896 90)
			(unlocked yes)
			(layer "F.Fab")
			(hide yes)
			(effects
				(font
					(size 1.016 1.016)
					(thickness 0.1524)
				)
			)
		)
		(property "Device Type" "R402H14"
			(at 0.064008 -5.517896 90)
			(unlocked yes)
			(layer "F.Fab")
			(hide yes)
			(effects
				(font
					(size 1.016 1.016)
					(thickness 0.1524)
				)
			)
		)
		(duplicate_pad_numbers_are_jumpers no)
		(fp_line
			(start 0.508 -0.9398)
			(end -0.508 -0.9398)
			(stroke
				(width 0.1524)
				(type default)
			)
			(layer "F.SilkS")
		)
		(fp_line
			(start -0.508 -0.9398)
			(end -0.508 0.9398)
			(stroke
				(width 0.1524)
				(type default)
			)
			(layer "F.SilkS")
		)
		(fp_rect
			(start -0.508 0.9398)
			(end 0.508 -0.9398)
			(stroke
				(width 0)
				(type default)
			)
			(fill no)
			(layer "F.CrtYd")
		)
		(fp_rect
			(start -0.508 0.9398)
			(end 0.508 -0.9398)
			(stroke
				(width 0)
				(type default)
			)
			(fill no)
			(layer "F.Fab")
		)
		(pad "1" smd custom
			(at 0 -0.4445 90)
			(size 0.1397 0.1397)
			(layers "F.Cu" "F.Mask" "F.Paste")
			(net "P12VL_2490_GATE")
			(options
				(clearance outline)
				(anchor circle)
			)
			(primitives
				(gr_poly
					(pts
						(arc
							(start -0.1778 -0.2794)
							(mid -0.249642 -0.249642)
							(end -0.2794 -0.1778)
						)
						(arc
							(start -0.2794 0.1778)
							(mid -0.249642 0.249642)
							(end -0.1778 0.2794)
						)
						(arc
							(start 0.1778 0.2794)
							(mid 0.249642 0.249642)
							(end 0.2794 0.1778)
						)
						(arc
							(start 0.2794 -0.1778)
							(mid 0.249642 -0.249642)
							(end 0.1778 -0.2794)
						)
					)
					(width 0)
					(fill yes)
				)
			)
		)
		(pad "2" smd custom
			(at 0 0.4445 90)
			(size 0.1397 0.1397)
			(layers "F.Cu" "F.Mask" "F.Paste")
			(net "P12VL_2490_RC")
			(options
				(clearance outline)
				(anchor circle)
			)
			(primitives
				(gr_poly
					(pts
						(arc
							(start -0.1778 -0.2794)
							(mid -0.249642 -0.249642)
							(end -0.2794 -0.1778)
						)
						(arc
							(start -0.2794 0.1778)
							(mid -0.249642 0.249642)
							(end -0.1778 0.2794)
						)
						(arc
							(start 0.1778 0.2794)
							(mid 0.249642 0.249642)
							(end 0.2794 0.1778)
						)
						(arc
							(start 0.2794 -0.1778)
							(mid 0.249642 -0.249642)
							(end 0.1778 -0.2794)
						)
					)
					(width 0)
					(fill yes)
				)
			)
		)
	)
	(footprint ""
		(layer "F.Cu")
		(at 22.86 -122.555)
		(property "Reference" "PR61"
			(at 0 0 0)
			(layer "F.SilkS")
			(hide yes)
			(effects
				(font
					(size 1.27 1.27)
				)
			)
		)
		(property "Value" "D002R2512F-GP"
			(at -3.228594 -1.194054 0)
			(unlocked yes)
			(layer "F.Fab")
			(hide yes)
			(effects
				(font
					(size 1.016 1.016)
					(thickness 0.1524)
				)
			)
		)
		(property "Device Type" "R2512-2H32"
			(at -3.228594 -2.718054 0)
			(unlocked yes)
			(layer "F.Fab")
			(hide yes)
			(effects
				(font
					(size 1.016 1.016)
					(thickness 0.1524)
				)
			)
		)
		(duplicate_pad_numbers_are_jumpers no)
		(fp_line
			(start -1.9685 -3.81)
			(end 1.9685 -3.81)
			(stroke
				(width 0.1524)
				(type default)
			)
			(layer "F.SilkS")
		)
		(fp_line
			(start -1.9685 3.81)
			(end -1.9685 -3.81)
			(stroke
				(width 0.1524)
				(type default)
			)
			(layer "F.SilkS")
		)
		(fp_line
			(start 1.9685 -3.81)
			(end 1.9685 3.81)
			(stroke
				(width 0.1524)
				(type default)
			)
			(layer "F.SilkS")
		)
		(fp_line
			(start 1.9685 3.81)
			(end -1.9685 3.81)
			(stroke
				(width 0.1524)
				(type default)
			)
			(layer "F.SilkS")
		)
		(fp_rect
			(start -1.5875 3.175)
			(end 1.5875 -3.175)
			(stroke
				(width 0)
				(type default)
			)
			(fill no)
			(layer "F.CrtYd")
		)
		(fp_poly
			(pts
				(xy -2.2225 3.8862) (xy -2.2225 0.00254) (xy -1.5875 0.00254) (xy -1.5875 3.175) (xy 1.5875 3.175)
				(xy 1.5875 -3.175) (xy -1.5875 -3.175) (xy -1.5875 -0.00254) (xy -2.2225 -0.00254) (xy -2.2225 -3.8862)
				(xy 2.2225 -3.8862) (xy 2.2225 3.8862)
			)
			(stroke
				(width 0)
				(type default)
			)
			(fill no)
			(layer "F.CrtYd")
		)
		(fp_rect
			(start -2.2225 3.8862)
			(end 2.2225 -3.8862)
			(stroke
				(width 0)
				(type default)
			)
			(fill no)
			(layer "F.Fab")
		)
		(pad "1" smd rect
			(at 0 -2.273808)
			(size 3.429 2.5654)
			(layers "F.Cu" "F.Mask" "F.Paste")
			(net "P12V")
		)
		(pad "2" smd rect
			(at 0 2.273808)
			(size 3.429 2.5654)
			(layers "F.Cu" "F.Mask" "F.Paste")
			(net "P12VU_NET")
		)
	)
	(footprint ""
		(layer "F.Cu")
		(at 44.831 -111.633)
		(property "Reference" "PQ12"
			(at 0 0 0)
			(layer "F.SilkS")
			(hide yes)
			(effects
				(font
					(size 1.27 1.27)
				)
			)
		)
		(property "Value" "PH0925CL-GP"
			(at -4.2799 -0.4572 0)
			(unlocked yes)
			(layer "F.Fab")
			(hide yes)
			(effects
				(font
					(size 1.016 1.016)
					(thickness 0.1524)
				)
			)
		)
		(property "Device Type" "LFPAK-5PH48-U"
			(at -4.2799 -1.9812 0)
			(unlocked yes)
			(layer "F.Fab")
			(hide yes)
			(effects
				(font
					(size 1.016 1.016)
					(thickness 0.1524)
				)
			)
		)
		(duplicate_pad_numbers_are_jumpers no)
		(fp_line
			(start -2.7559 -6.5532)
			(end -2.7559 1.0668)
			(stroke
				(width 0.1524)
				(type default)
			)
			(layer "F.SilkS")
		)
		(fp_line
			(start -2.7559 1.0668)
			(end 2.7559 1.0668)
			(stroke
				(width 0.1524)
				(type default)
			)
			(layer "F.SilkS")
		)
		(fp_line
			(start -1.7272 1.1684)
			(end -2.1082 1.1684)
			(stroke
				(width 0.3302)
				(type default)
			)
			(layer "F.SilkS")
		)
		(fp_line
			(start 2.7559 -6.5532)
			(end -2.7559 -6.5532)
			(stroke
				(width 0.1524)
				(type default)
			)
			(layer "F.SilkS")
		)
		(fp_line
			(start 2.7559 1.0668)
			(end 2.7559 -6.5532)
			(stroke
				(width 0.1524)
				(type default)
			)
			(layer "F.SilkS")
		)
		(fp_poly
			(pts
				(xy -2.3368 1.5748) (xy -1.905 1.143) (xy -1.4732 1.5748)
			)
			(stroke
				(width 0)
				(type default)
			)
			(fill yes)
			(layer "F.SilkS")
		)
		(fp_poly
			(pts
				(xy -2.5019 -4.02971) (xy -0.3302 -4.02971) (xy -0.3302 -6.30301) (xy -2.5019 -6.30301)
			)
			(stroke
				(width 0)
				(type default)
			)
			(fill yes)
			(layer "F.Paste")
		)
		(fp_poly
			(pts
				(xy -2.5019 -1.09601) (xy -0.3302 -1.09601) (xy -0.3302 -3.36931) (xy -2.5019 -3.36931)
			)
			(stroke
				(width 0)
				(type default)
			)
			(fill yes)
			(layer "F.Paste")
		)
		(fp_poly
			(pts
				(xy 0.3302 -4.02971) (xy 2.5019 -4.02971) (xy 2.5019 -6.30301) (xy 0.3302 -6.30301)
			)
			(stroke
				(width 0)
				(type default)
			)
			(fill yes)
			(layer "F.Paste")
		)
		(fp_poly
			(pts
				(xy 0.3302 -1.09601) (xy 2.5019 -1.09601) (xy 2.5019 -3.36931) (xy 0.3302 -3.36931)
			)
			(stroke
				(width 0)
				(type default)
			)
			(fill yes)
			(layer "F.Paste")
		)
		(fp_rect
			(start -2.4511 0.3048)
			(end 2.4511 -5.6896)
			(stroke
				(width 0)
				(type default)
			)
			(fill no)
			(layer "F.CrtYd")
		)
		(fp_poly
			(pts
				(xy -3.0099 1.3208) (xy -3.0099 -6.8072) (xy 3.0099 -6.8072) (xy 3.0099 -1.016) (xy 2.4511 -1.016)
				(xy 2.4511 -5.6896) (xy -2.4511 -5.6896) (xy -2.4511 0.3048) (xy 2.4511 0.3048) (xy 2.4511 -1.0033)
				(xy 3.0099 -1.0033) (xy 3.0099 1.3208)
			)
			(stroke
				(width 0)
				(type default)
			)
			(fill no)
			(layer "F.CrtYd")
		)
		(fp_rect
			(start -3.0099 1.3208)
			(end 3.0099 -6.8072)
			(stroke
				(width 0)
				(type default)
			)
			(fill no)
			(layer "F.Fab")
		)
		(pad "1" smd rect
			(at -1.905 0)
			(size 0.762 1.6256)
			(layers "F.Cu" "F.Mask" "F.Paste")
			(net "P12VL")
		)
		(pad "2" smd rect
			(at -0.635 0)
			(size 0.762 1.6256)
			(layers "F.Cu" "F.Mask" "F.Paste")
			(net "P12VL")
		)
		(pad "3" smd rect
			(at 0.635 0)
			(size 0.762 1.6256)
			(layers "F.Cu" "F.Mask" "F.Paste")
			(net "P12VL")
		)
		(pad "4" smd rect
			(at 1.905 0)
			(size 0.762 1.6256)
			(layers "F.Cu" "F.Mask" "F.Paste")
			(net "P12VL_2490_GATE_DRV_2")
		)
		(pad "5" smd rect
			(at 0 -3.69951)
			(size 5.0038 5.207)
			(layers "F.Cu" "F.Mask" "F.Paste")
			(net "P12VL_NET")
		)
	)
	(footprint ""
		(layer "F.Cu")
		(at 20.385024 -175.37811 90)
		(property "Reference" "R23"
			(at 0 0 90)
			(layer "F.SilkS")
			(hide yes)
			(effects
				(font
					(size 1.27 1.27)
				)
			)
		)
		(property "Value" "4K7R2F-GP"
			(at 0.064008 -3.993896 90)
			(unlocked yes)
			(layer "F.Fab")
			(hide yes)
			(effects
				(font
					(size 1.016 1.016)
					(thickness 0.1524)
				)
			)
		)
		(property "Device Type" "R402H16"
			(at 0.064008 -5.517896 90)
			(unlocked yes)
			(layer "F.Fab")
			(hide yes)
			(effects
				(font
					(size 1.016 1.016)
					(thickness 0.1524)
				)
			)
		)
		(duplicate_pad_numbers_are_jumpers no)
		(fp_line
			(start 0.508 -0.9398)
			(end -0.508 -0.9398)
			(stroke
				(width 0.1524)
				(type default)
			)
			(layer "F.SilkS")
		)
		(fp_line
			(start -0.508 -0.9398)
			(end -0.508 0.9398)
			(stroke
				(width 0.1524)
				(type default)
			)
			(layer "F.SilkS")
		)
		(fp_rect
			(start -0.508 0.9398)
			(end 0.508 -0.9398)
			(stroke
				(width 0)
				(type default)
			)
			(fill no)
			(layer "F.CrtYd")
		)
		(fp_rect
			(start -0.508 0.9398)
			(end 0.508 -0.9398)
			(stroke
				(width 0)
				(type default)
			)
			(fill no)
			(layer "F.Fab")
		)
		(pad "1" smd custom
			(at 0 -0.4445 90)
			(size 0.1397 0.1397)
			(layers "F.Cu" "F.Mask" "F.Paste")
			(net "P3V3")
			(options
				(clearance outline)
				(anchor circle)
			)
			(primitives
				(gr_poly
					(pts
						(arc
							(start -0.1778 -0.2794)
							(mid -0.249642 -0.249642)
							(end -0.2794 -0.1778)
						)
						(arc
							(start -0.2794 0.1778)
							(mid -0.249642 0.249642)
							(end -0.1778 0.2794)
						)
						(arc
							(start 0.1778 0.2794)
							(mid 0.249642 0.249642)
							(end 0.2794 0.1778)
						)
						(arc
							(start 0.2794 -0.1778)
							(mid 0.249642 -0.249642)
							(end 0.1778 -0.2794)
						)
					)
					(width 0)
					(fill yes)
				)
			)
		)
		(pad "2" smd custom
			(at 0 0.4445 90)
			(size 0.1397 0.1397)
			(layers "F.Cu" "F.Mask" "F.Paste")
			(net "NCT7368S_SEL")
			(options
				(clearance outline)
				(anchor circle)
			)
			(primitives
				(gr_poly
					(pts
						(arc
							(start -0.1778 -0.2794)
							(mid -0.249642 -0.249642)
							(end -0.2794 -0.1778)
						)
						(arc
							(start -0.2794 0.1778)
							(mid -0.249642 0.249642)
							(end -0.1778 0.2794)
						)
						(arc
							(start 0.1778 0.2794)
							(mid 0.249642 0.249642)
							(end 0.2794 0.1778)
						)
						(arc
							(start 0.2794 -0.1778)
							(mid 0.249642 -0.249642)
							(end 0.1778 -0.2794)
						)
					)
					(width 0)
					(fill yes)
				)
			)
		)
	)
	(footprint ""
		(layer "F.Cu")
		(at 31.877 -22.479 90)
		(property "Reference" "TC13"
			(at 0 0 90)
			(layer "F.SilkS")
			(hide yes)
			(effects
				(font
					(size 1.27 1.27)
				)
			)
		)
		(property "Value" "ST15U25VDM-1-GP"
			(at 0 -9.6012 90)
			(unlocked yes)
			(layer "F.Fab")
			(hide yes)
			(effects
				(font
					(size 1.016 1.016)
					(thickness 0.1524)
				)
			)
		)
		(property "Device Type" "CT7343H79"
			(at 0 -11.1252 90)
			(unlocked yes)
			(layer "F.Fab")
			(hide yes)
			(effects
				(font
					(size 1.016 1.016)
					(thickness 0.1524)
				)
			)
		)
		(duplicate_pad_numbers_are_jumpers no)
		(fp_line
			(start 2.286 -4.8768)
			(end -2.286 -4.8768)
			(stroke
				(width 0.1524)
				(type default)
			)
			(layer "F.SilkS")
		)
		(fp_line
			(start -2.286 -4.8768)
			(end -2.286 -2.032)
			(stroke
				(width 0.1524)
				(type default)
			)
			(layer "F.SilkS")
		)
		(fp_line
			(start 2.1082 -4.699)
			(end -2.1082 -4.699)
			(stroke
				(width 0.508)
				(type default)
			)
			(layer "F.SilkS")
		)
		(fp_line
			(start 2.286 -2.032)
			(end 2.286 -4.8768)
			(stroke
				(width 0.1524)
				(type default)
			)
			(layer "F.SilkS")
		)
		(fp_line
			(start 2.286 2.032)
			(end 2.286 4.8768)
			(stroke
				(width 0.1524)
				(type default)
			)
			(layer "F.SilkS")
		)
		(fp_line
			(start 2.286 4.8768)
			(end -2.286 4.8768)
			(stroke
				(width 0.1524)
				(type default)
			)
			(layer "F.SilkS")
		)
		(fp_line
			(start -2.286 4.8768)
			(end -2.286 2.032)
			(stroke
				(width 0.1524)
				(type default)
			)
			(layer "F.SilkS")
		)
		(fp_rect
			(start -2.1463 3.6449)
			(end 2.1463 -3.6449)
			(stroke
				(width 0)
				(type default)
			)
			(fill no)
			(layer "F.CrtYd")
		)
		(fp_poly
			(pts
				(xy -2.54 4.953) (xy -2.54 4.2926) (xy -3.81 4.2926) (xy -3.81 -4.2926) (xy -2.54 -4.2926) (xy -2.54 -4.953)
				(xy 2.54 -4.953) (xy 2.54 -4.2926) (xy 3.81 -4.2926) (xy 3.81 -1.6256) (xy 2.1463 -1.6256) (xy 2.1463 -3.6449)
				(xy -2.1463 -3.6449) (xy -2.1463 3.6449) (xy 2.1463 3.6449) (xy 2.1463 -1.6129) (xy 3.81 -1.6129)
				(xy 3.81 4.2926) (xy 2.54 4.2926) (xy 2.54 4.953)
			)
			(stroke
				(width 0)
				(type default)
			)
			(fill no)
			(layer "F.CrtYd")
		)
		(fp_rect
			(start 2.54 4.2926)
			(end 3.81 -4.2926)
			(stroke
				(width 0)
				(type default)
			)
			(fill no)
			(layer "F.Fab")
		)
		(fp_rect
			(start -3.81 4.2926)
			(end -2.54 -4.2926)
			(stroke
				(width 0)
				(type default)
			)
			(fill no)
			(layer "F.Fab")
		)
		(fp_rect
			(start -2.54 4.953)
			(end 2.54 -4.953)
			(stroke
				(width 0)
				(type default)
			)
			(fill no)
			(layer "F.Fab")
		)
		(pad "1" smd rect
			(at 0 -3.1496 90)
			(size 2.413 2.286)
			(layers "F.Cu" "F.Mask" "F.Paste")
			(net "P12V")
		)
		(pad "2" smd rect
			(at 0 3.1496 90)
			(size 2.413 2.286)
			(layers "F.Cu" "F.Mask" "F.Paste")
			(net "GND")
		)
		(zone
			(layer "F.Cu")
			(hatch none 0.5)
			(connect_pads
				(clearance 0)
			)
			(min_thickness 0.25)
			(keepout
				(tracks allowed)
				(vias not_allowed)
				(pads allowed)
				(copperpour not_allowed)
				(footprints allowed)
			)
			(placement
				(enabled no)
				(sheetname "")
			)
			(fill
				(thermal_gap 0.5)
				(thermal_bridge_width 0.5)
				(island_removal_mode 0)
			)
			(polygon
				(pts
					(xy 30.1879 -23.9903) (xy 27.2796 -23.9903) (xy 27.2796 -20.9677) (xy 30.1752 -20.9677) (xy 30.5054 -20.9677)
					(xy 30.5054 -23.9903)
				)
			)
		)
		(zone
			(layer "F.Cu")
			(hatch none 0.5)
			(connect_pads
				(clearance 0)
			)
			(min_thickness 0.25)
			(keepout
				(tracks allowed)
				(vias not_allowed)
				(pads allowed)
				(copperpour not_allowed)
				(footprints allowed)
			)
			(placement
				(enabled no)
				(sheetname "")
			)
			(fill
				(thermal_gap 0.5)
				(thermal_bridge_width 0.5)
				(island_removal_mode 0)
			)
			(polygon
				(pts
					(xy 36.4744 -20.9677) (xy 36.4744 -23.9903) (xy 33.5788 -23.9903) (xy 33.2486 -23.9903) (xy 33.2486 -20.9677)
					(xy 33.5788 -20.9677)
				)
			)
		)
	)
)
